(kicad_pcb
	(version 20260206)
	(generator "pcbnew")
	(generator_version "10.0")
	(general
		(thickness 1.6)
		(legacy_teardrops no)
	)
	(paper "A4")
	(title_block
		(title "04192023_DAF0TMB3IC0_F0TG_MB_C_brd_V02_OCP.brd")
		(comment 1 "Grand Teton / footprints 6390-6396 of 8354")
	)
	(layers
		(0 "F.Cu" signal "TOP")
		(4 "In1.Cu" signal "GND")
		(6 "In2.Cu" signal "IN1")
		(8 "In3.Cu" signal "GND1")
		(10 "In4.Cu" signal "IN2")
		(12 "In5.Cu" signal "GND2")
		(14 "In6.Cu" signal "IN3")
		(16 "In7.Cu" signal "GND3")
		(18 "In8.Cu" signal "VCC")
		(20 "In9.Cu" signal "VCC1")
		(22 "In10.Cu" signal "GND4")
		(24 "In11.Cu" signal "IN4")
		(26 "In12.Cu" signal "GND5")
		(28 "In13.Cu" signal "IN5")
		(30 "In14.Cu" signal "GND6")
		(32 "In15.Cu" signal "IN6")
		(34 "In16.Cu" signal "GND7")
		(2 "B.Cu" signal "BOTTOM")
		(9 "F.Adhes" user "F.Adhesive")
		(11 "B.Adhes" user "B.Adhesive")
		(13 "F.Paste" user "Package Geometry/Pastemask Top")
		(15 "B.Paste" user "Package Geometry/Pastemask Bottom")
		(5 "F.SilkS" user "Ref Des/Silkscreen Top")
		(7 "B.SilkS" user "Ref Des/Silkscreen Bottom")
		(1 "F.Mask" user "Board Geometry/Soldermask Top")
		(3 "B.Mask" user "Board Geometry/Soldermask Bottom")
		(17 "Dwgs.User" user "User.Drawings")
		(19 "Cmts.User" user "User.Comments")
		(21 "Eco1.User" user "User.Eco1")
		(23 "Eco2.User" user "User.Eco2")
		(25 "Edge.Cuts" user "Board Geometry/Outline")
		(27 "Margin" user)
		(31 "F.CrtYd" user "Package Geometry/Place Bound Top")
		(29 "B.CrtYd" user "Package Geometry/Place Bound Bottom")
		(35 "F.Fab" user "Ref Des/Assembly Top")
		(33 "B.Fab" user "Ref Des/Assembly Bottom")
	)
	(footprint ""
		(layer "B.Cu")
		(at 123.611386 -258.830318)
		(property "Reference" "C2461"
			(at 0 0 0)
			(layer "B.SilkS")
			(hide yes)
			(effects
				(font
					(size 1.27 1.27)
				)
				(justify mirror)
			)
		)
		(property "Value" ""
			(at 0 0 0)
			(layer "B.Fab")
			(effects
				(font
					(size 1.27 1.27)
				)
				(justify mirror)
			)
		)
		(duplicate_pad_numbers_are_jumpers no)
		(fp_line
			(start -0.7874 -0.4064)
			(end -0.7874 0.4064)
			(stroke
				(width 0.1524)
				(type default)
			)
			(layer "B.SilkS")
		)
		(fp_line
			(start -0.7874 0.4064)
			(end 0.7874 0.4064)
			(stroke
				(width 0.1524)
				(type default)
			)
			(layer "B.SilkS")
		)
		(fp_line
			(start 0.7874 -0.4064)
			(end -0.7874 -0.4064)
			(stroke
				(width 0.1524)
				(type default)
			)
			(layer "B.SilkS")
		)
		(fp_line
			(start 0.7874 0.4064)
			(end 0.7874 -0.4064)
			(stroke
				(width 0.1524)
				(type default)
			)
			(layer "B.SilkS")
		)
		(fp_line
			(start -0.67945 -0.3048)
			(end -0.67945 0.3048)
			(stroke
				(width 0.1)
				(type default)
			)
			(layer "B.Fab")
		)
		(fp_line
			(start -0.67945 0.3048)
			(end -0.120396 0.3048)
			(stroke
				(width 0.1)
				(type default)
			)
			(layer "B.Fab")
		)
		(fp_line
			(start -0.12065 -0.3048)
			(end -0.67945 -0.3048)
			(stroke
				(width 0.1)
				(type default)
			)
			(layer "B.Fab")
		)
		(fp_line
			(start -0.12065 -0.2794)
			(end -0.12065 -0.3048)
			(stroke
				(width 0.1)
				(type default)
			)
			(layer "B.Fab")
		)
		(fp_line
			(start -0.120396 0.2794)
			(end 0.12065 0.2794)
			(stroke
				(width 0.1)
				(type default)
			)
			(layer "B.Fab")
		)
		(fp_line
			(start -0.120396 0.3048)
			(end -0.120396 0.2794)
			(stroke
				(width 0.1)
				(type default)
			)
			(layer "B.Fab")
		)
		(fp_line
			(start 0.12065 -0.305054)
			(end 0.12065 -0.2794)
			(stroke
				(width 0.1)
				(type default)
			)
			(layer "B.Fab")
		)
		(fp_line
			(start 0.12065 -0.2794)
			(end -0.12065 -0.2794)
			(stroke
				(width 0.1)
				(type default)
			)
			(layer "B.Fab")
		)
		(fp_line
			(start 0.12065 0.2794)
			(end 0.12065 0.3048)
			(stroke
				(width 0.1)
				(type default)
			)
			(layer "B.Fab")
		)
		(fp_line
			(start 0.12065 0.3048)
			(end 0.67945 0.3048)
			(stroke
				(width 0.1)
				(type default)
			)
			(layer "B.Fab")
		)
		(fp_line
			(start 0.67945 -0.305054)
			(end 0.12065 -0.305054)
			(stroke
				(width 0.1)
				(type default)
			)
			(layer "B.Fab")
		)
		(fp_line
			(start 0.67945 0.3048)
			(end 0.67945 -0.305054)
			(stroke
				(width 0.1)
				(type default)
			)
			(layer "B.Fab")
		)
		(pad "1" smd circle
			(at 0.40005 0 180)
			(size 0 0)
			(layers "B.Cu" "B.Mask" "B.Paste")
			(net "PVDDCR_SOC_P1")
		)
		(pad "2" smd circle
			(at -0.40005 0 180)
			(size 0 0)
			(layers "B.Cu" "B.Mask" "B.Paste")
			(net "GND")
		)
	)
	(footprint ""
		(layer "B.Cu")
		(at 19.91487 -388.789926 90)
		(property "Reference" "PC6614_1"
			(at 0 0 90)
			(layer "B.SilkS")
			(hide yes)
			(effects
				(font
					(size 1.27 1.27)
				)
				(justify mirror)
			)
		)
		(property "Value" ""
			(at 0 0 90)
			(layer "B.Fab")
			(effects
				(font
					(size 1.27 1.27)
				)
				(justify mirror)
			)
		)
		(duplicate_pad_numbers_are_jumpers no)
		(fp_line
			(start 1.524 -0.762)
			(end -1.524 -0.762)
			(stroke
				(width 0.1524)
				(type default)
			)
			(layer "B.SilkS")
		)
		(fp_line
			(start -1.524 -0.762)
			(end -1.524 0.762)
			(stroke
				(width 0.1524)
				(type default)
			)
			(layer "B.SilkS")
		)
		(fp_line
			(start 1.524 0.762)
			(end 1.524 -0.762)
			(stroke
				(width 0.1524)
				(type default)
			)
			(layer "B.SilkS")
		)
		(fp_line
			(start -1.524 0.762)
			(end 1.524 0.762)
			(stroke
				(width 0.1524)
				(type default)
			)
			(layer "B.SilkS")
		)
		(fp_line
			(start 1.1049 -0.724916)
			(end 1.1049 0.724916)
			(stroke
				(width 0.1)
				(type default)
			)
			(layer "B.Fab")
		)
		(fp_line
			(start -1.1049 -0.724916)
			(end 1.1049 -0.724916)
			(stroke
				(width 0.1)
				(type default)
			)
			(layer "B.Fab")
		)
		(fp_line
			(start 1.1049 0.724916)
			(end -1.1049 0.724916)
			(stroke
				(width 0.1)
				(type default)
			)
			(layer "B.Fab")
		)
		(fp_line
			(start -1.1049 0.724916)
			(end -1.1049 -0.724916)
			(stroke
				(width 0.1)
				(type default)
			)
			(layer "B.Fab")
		)
		(pad "1" smd rect
			(at 0.889 0 90)
			(size 1.016 1.27)
			(layers "B.Cu" "B.Mask" "B.Paste")
			(net "SW_P12V_AUX_P0V9_RETIMER_CPU1_FLT")
		)
		(pad "2" smd rect
			(at -0.889 0 90)
			(size 1.016 1.27)
			(layers "B.Cu" "B.Mask" "B.Paste")
			(net "GND")
		)
	)
	(footprint ""
		(layer "B.Cu")
		(at 400.964146 -354.439728 -90)
		(property "Reference" "R6129"
			(at 0 0 90)
			(layer "B.SilkS")
			(hide yes)
			(effects
				(font
					(size 1.27 1.27)
				)
				(justify mirror)
			)
		)
		(property "Value" ""
			(at 0 0 90)
			(layer "B.Fab")
			(effects
				(font
					(size 1.27 1.27)
				)
				(justify mirror)
			)
		)
		(duplicate_pad_numbers_are_jumpers no)
		(fp_line
			(start -0.7874 0.4064)
			(end 0.7874 0.4064)
			(stroke
				(width 0.1524)
				(type default)
			)
			(layer "B.SilkS")
		)
		(fp_line
			(start 0.7874 0.4064)
			(end 0.7874 -0.4064)
			(stroke
				(width 0.1524)
				(type default)
			)
			(layer "B.SilkS")
		)
		(fp_line
			(start -0.7874 -0.4064)
			(end -0.7874 0.4064)
			(stroke
				(width 0.1524)
				(type default)
			)
			(layer "B.SilkS")
		)
		(fp_line
			(start 0.7874 -0.4064)
			(end -0.7874 -0.4064)
			(stroke
				(width 0.1524)
				(type default)
			)
			(layer "B.SilkS")
		)
		(fp_line
			(start -0.67945 0.3048)
			(end -0.120396 0.3048)
			(stroke
				(width 0.1)
				(type default)
			)
			(layer "B.Fab")
		)
		(fp_line
			(start -0.120396 0.3048)
			(end -0.120396 0.2794)
			(stroke
				(width 0.1)
				(type default)
			)
			(layer "B.Fab")
		)
		(fp_line
			(start 0.12065 0.3048)
			(end 0.67945 0.3048)
			(stroke
				(width 0.1)
				(type default)
			)
			(layer "B.Fab")
		)
		(fp_line
			(start 0.67945 0.3048)
			(end 0.67945 -0.305054)
			(stroke
				(width 0.1)
				(type default)
			)
			(layer "B.Fab")
		)
		(fp_line
			(start -0.120396 0.2794)
			(end 0.12065 0.2794)
			(stroke
				(width 0.1)
				(type default)
			)
			(layer "B.Fab")
		)
		(fp_line
			(start 0.12065 0.2794)
			(end 0.12065 0.3048)
			(stroke
				(width 0.1)
				(type default)
			)
			(layer "B.Fab")
		)
		(fp_line
			(start -0.12065 -0.2794)
			(end -0.12065 -0.3048)
			(stroke
				(width 0.1)
				(type default)
			)
			(layer "B.Fab")
		)
		(fp_line
			(start 0.12065 -0.2794)
			(end -0.12065 -0.2794)
			(stroke
				(width 0.1)
				(type default)
			)
			(layer "B.Fab")
		)
		(fp_line
			(start -0.67945 -0.3048)
			(end -0.67945 0.3048)
			(stroke
				(width 0.1)
				(type default)
			)
			(layer "B.Fab")
		)
		(fp_line
			(start -0.12065 -0.3048)
			(end -0.67945 -0.3048)
			(stroke
				(width 0.1)
				(type default)
			)
			(layer "B.Fab")
		)
		(fp_line
			(start 0.12065 -0.305054)
			(end 0.12065 -0.2794)
			(stroke
				(width 0.1)
				(type default)
			)
			(layer "B.Fab")
		)
		(fp_line
			(start 0.67945 -0.305054)
			(end 0.12065 -0.305054)
			(stroke
				(width 0.1)
				(type default)
			)
			(layer "B.Fab")
		)
		(pad "1" smd circle
			(at 0.40005 0 90)
			(size 0 0)
			(layers "B.Cu" "B.Mask" "B.Paste")
			(net "FM_BOARD_SKU_ID0")
		)
		(pad "2" smd circle
			(at -0.40005 0 90)
			(size 0 0)
			(layers "B.Cu" "B.Mask" "B.Paste")
			(net "GND")
		)
	)
	(footprint ""
		(layer "B.Cu")
		(at 365.835692 -261.255002)
		(property "Reference" "C2594"
			(at 0 0 0)
			(layer "B.SilkS")
			(hide yes)
			(effects
				(font
					(size 1.27 1.27)
				)
				(justify mirror)
			)
		)
		(property "Value" ""
			(at 0 0 0)
			(layer "B.Fab")
			(effects
				(font
					(size 1.27 1.27)
				)
				(justify mirror)
			)
		)
		(duplicate_pad_numbers_are_jumpers no)
		(fp_line
			(start -0.7874 -0.4064)
			(end -0.7874 0.4064)
			(stroke
				(width 0.1524)
				(type default)
			)
			(layer "B.SilkS")
		)
		(fp_line
			(start -0.7874 0.4064)
			(end 0.7874 0.4064)
			(stroke
				(width 0.1524)
				(type default)
			)
			(layer "B.SilkS")
		)
		(fp_line
			(start 0.7874 -0.4064)
			(end -0.7874 -0.4064)
			(stroke
				(width 0.1524)
				(type default)
			)
			(layer "B.SilkS")
		)
		(fp_line
			(start 0.7874 0.4064)
			(end 0.7874 -0.4064)
			(stroke
				(width 0.1524)
				(type default)
			)
			(layer "B.SilkS")
		)
		(fp_line
			(start -0.67945 -0.3048)
			(end -0.67945 0.3048)
			(stroke
				(width 0.1)
				(type default)
			)
			(layer "B.Fab")
		)
		(fp_line
			(start -0.67945 0.3048)
			(end -0.120396 0.3048)
			(stroke
				(width 0.1)
				(type default)
			)
			(layer "B.Fab")
		)
		(fp_line
			(start -0.12065 -0.3048)
			(end -0.67945 -0.3048)
			(stroke
				(width 0.1)
				(type default)
			)
			(layer "B.Fab")
		)
		(fp_line
			(start -0.12065 -0.2794)
			(end -0.12065 -0.3048)
			(stroke
				(width 0.1)
				(type default)
			)
			(layer "B.Fab")
		)
		(fp_line
			(start -0.120396 0.2794)
			(end 0.12065 0.2794)
			(stroke
				(width 0.1)
				(type default)
			)
			(layer "B.Fab")
		)
		(fp_line
			(start -0.120396 0.3048)
			(end -0.120396 0.2794)
			(stroke
				(width 0.1)
				(type default)
			)
			(layer "B.Fab")
		)
		(fp_line
			(start 0.12065 -0.305054)
			(end 0.12065 -0.2794)
			(stroke
				(width 0.1)
				(type default)
			)
			(layer "B.Fab")
		)
		(fp_line
			(start 0.12065 -0.2794)
			(end -0.12065 -0.2794)
			(stroke
				(width 0.1)
				(type default)
			)
			(layer "B.Fab")
		)
		(fp_line
			(start 0.12065 0.2794)
			(end 0.12065 0.3048)
			(stroke
				(width 0.1)
				(type default)
			)
			(layer "B.Fab")
		)
		(fp_line
			(start 0.12065 0.3048)
			(end 0.67945 0.3048)
			(stroke
				(width 0.1)
				(type default)
			)
			(layer "B.Fab")
		)
		(fp_line
			(start 0.67945 -0.305054)
			(end 0.12065 -0.305054)
			(stroke
				(width 0.1)
				(type default)
			)
			(layer "B.Fab")
		)
		(fp_line
			(start 0.67945 0.3048)
			(end 0.67945 -0.305054)
			(stroke
				(width 0.1)
				(type default)
			)
			(layer "B.Fab")
		)
		(pad "1" smd circle
			(at 0.40005 0 180)
			(size 0 0)
			(layers "B.Cu" "B.Mask" "B.Paste")
			(net "PVDDCR_SOC_P0")
		)
		(pad "2" smd circle
			(at -0.40005 0 180)
			(size 0 0)
			(layers "B.Cu" "B.Mask" "B.Paste")
			(net "GND")
		)
	)
	(footprint ""
		(layer "B.Cu")
		(at 303.614582 -346.784168 90)
		(property "Reference" "PC158_1"
			(at 0 0 90)
			(layer "B.SilkS")
			(hide yes)
			(effects
				(font
					(size 1.27 1.27)
				)
				(justify mirror)
			)
		)
		(property "Value" ""
			(at 0 0 90)
			(layer "B.Fab")
			(effects
				(font
					(size 1.27 1.27)
				)
				(justify mirror)
			)
		)
		(duplicate_pad_numbers_are_jumpers no)
		(fp_line
			(start 1.524 -0.762)
			(end -1.524 -0.762)
			(stroke
				(width 0.1524)
				(type default)
			)
			(layer "B.SilkS")
		)
		(fp_line
			(start -1.524 -0.762)
			(end -1.524 0.762)
			(stroke
				(width 0.1524)
				(type default)
			)
			(layer "B.SilkS")
		)
		(fp_line
			(start 1.524 0.762)
			(end 1.524 -0.762)
			(stroke
				(width 0.1524)
				(type default)
			)
			(layer "B.SilkS")
		)
		(fp_line
			(start -1.524 0.762)
			(end 1.524 0.762)
			(stroke
				(width 0.1524)
				(type default)
			)
			(layer "B.SilkS")
		)
		(fp_line
			(start 1.1049 -0.724916)
			(end 1.1049 0.724916)
			(stroke
				(width 0.1)
				(type default)
			)
			(layer "B.Fab")
		)
		(fp_line
			(start -1.1049 -0.724916)
			(end 1.1049 -0.724916)
			(stroke
				(width 0.1)
				(type default)
			)
			(layer "B.Fab")
		)
		(fp_line
			(start 1.1049 0.724916)
			(end -1.1049 0.724916)
			(stroke
				(width 0.1)
				(type default)
			)
			(layer "B.Fab")
		)
		(fp_line
			(start -1.1049 0.724916)
			(end -1.1049 -0.724916)
			(stroke
				(width 0.1)
				(type default)
			)
			(layer "B.Fab")
		)
		(pad "1" smd rect
			(at 0.889 0 90)
			(size 1.016 1.27)
			(layers "B.Cu" "B.Mask" "B.Paste")
			(net "SW_P12V_AUX_PVDDIO_P0_FLT")
		)
		(pad "2" smd rect
			(at -0.889 0 90)
			(size 1.016 1.27)
			(layers "B.Cu" "B.Mask" "B.Paste")
			(net "GND")
		)
	)
	(footprint ""
		(layer "B.Cu")
		(at 164.403532 -435.93258 -90)
		(property "Reference" "C13"
			(at 0 0 90)
			(layer "B.SilkS")
			(hide yes)
			(effects
				(font
					(size 1.27 1.27)
				)
				(justify mirror)
			)
		)
		(property "Value" ""
			(at 0 0 90)
			(layer "B.Fab")
			(effects
				(font
					(size 1.27 1.27)
				)
				(justify mirror)
			)
		)
		(duplicate_pad_numbers_are_jumpers no)
		(fp_line
			(start -0.7874 0.4064)
			(end 0.7874 0.4064)
			(stroke
				(width 0.1524)
				(type default)
			)
			(layer "B.SilkS")
		)
		(fp_line
			(start 0.7874 0.4064)
			(end 0.7874 -0.4064)
			(stroke
				(width 0.1524)
				(type default)
			)
			(layer "B.SilkS")
		)
		(fp_line
			(start -0.7874 -0.4064)
			(end -0.7874 0.4064)
			(stroke
				(width 0.1524)
				(type default)
			)
			(layer "B.SilkS")
		)
		(fp_line
			(start 0.7874 -0.4064)
			(end -0.7874 -0.4064)
			(stroke
				(width 0.1524)
				(type default)
			)
			(layer "B.SilkS")
		)
		(fp_line
			(start -0.67945 0.3048)
			(end -0.120396 0.3048)
			(stroke
				(width 0.1)
				(type default)
			)
			(layer "B.Fab")
		)
		(fp_line
			(start -0.120396 0.3048)
			(end -0.120396 0.2794)
			(stroke
				(width 0.1)
				(type default)
			)
			(layer "B.Fab")
		)
		(fp_line
			(start 0.12065 0.3048)
			(end 0.67945 0.3048)
			(stroke
				(width 0.1)
				(type default)
			)
			(layer "B.Fab")
		)
		(fp_line
			(start 0.67945 0.3048)
			(end 0.67945 -0.305054)
			(stroke
				(width 0.1)
				(type default)
			)
			(layer "B.Fab")
		)
		(fp_line
			(start -0.120396 0.2794)
			(end 0.12065 0.2794)
			(stroke
				(width 0.1)
				(type default)
			)
			(layer "B.Fab")
		)
		(fp_line
			(start 0.12065 0.2794)
			(end 0.12065 0.3048)
			(stroke
				(width 0.1)
				(type default)
			)
			(layer "B.Fab")
		)
		(fp_line
			(start -0.12065 -0.2794)
			(end -0.12065 -0.3048)
			(stroke
				(width 0.1)
				(type default)
			)
			(layer "B.Fab")
		)
		(fp_line
			(start 0.12065 -0.2794)
			(end -0.12065 -0.2794)
			(stroke
				(width 0.1)
				(type default)
			)
			(layer "B.Fab")
		)
		(fp_line
			(start -0.67945 -0.3048)
			(end -0.67945 0.3048)
			(stroke
				(width 0.1)
				(type default)
			)
			(layer "B.Fab")
		)
		(fp_line
			(start -0.12065 -0.3048)
			(end -0.67945 -0.3048)
			(stroke
				(width 0.1)
				(type default)
			)
			(layer "B.Fab")
		)
		(fp_line
			(start 0.12065 -0.305054)
			(end 0.12065 -0.2794)
			(stroke
				(width 0.1)
				(type default)
			)
			(layer "B.Fab")
		)
		(fp_line
			(start 0.67945 -0.305054)
			(end 0.12065 -0.305054)
			(stroke
				(width 0.1)
				(type default)
			)
			(layer "B.Fab")
		)
		(pad "1" smd circle
			(at 0.40005 0 90)
			(size 0 0)
			(layers "B.Cu" "B.Mask" "B.Paste")
			(net "PRSNT_CABLE_GPU_B3_ISO_N")
		)
		(pad "2" smd circle
			(at -0.40005 0 90)
			(size 0 0)
			(layers "B.Cu" "B.Mask" "B.Paste")
			(net "GND")
		)
	)
	(footprint ""
		(layer "B.Cu")
		(at 359.721404 -252.41631 180)
		(property "Reference" "C3931"
			(at 0 0 0)
			(layer "B.SilkS")
			(hide yes)
			(effects
				(font
					(size 1.27 1.27)
				)
				(justify mirror)
			)
		)
		(property "Value" ""
			(at 0 0 0)
			(layer "B.Fab")
			(effects
				(font
					(size 1.27 1.27)
				)
				(justify mirror)
			)
		)
		(duplicate_pad_numbers_are_jumpers no)
		(fp_line
			(start 0.7874 0.4064)
			(end 0.7874 -0.4064)
			(stroke
				(width 0.1524)
				(type default)
			)
			(layer "B.SilkS")
		)
		(fp_line
			(start 0.7874 -0.4064)
			(end -0.7874 -0.4064)
			(stroke
				(width 0.1524)
				(type default)
			)
			(layer "B.SilkS")
		)
		(fp_line
			(start -0.7874 0.4064)
			(end 0.7874 0.4064)
			(stroke
				(width 0.1524)
				(type default)
			)
			(layer "B.SilkS")
		)
		(fp_line
			(start -0.7874 -0.4064)
			(end -0.7874 0.4064)
			(stroke
				(width 0.1524)
				(type default)
			)
			(layer "B.SilkS")
		)
		(fp_line
			(start 0.67945 0.3048)
			(end 0.67945 -0.305054)
			(stroke
				(width 0.1)
				(type default)
			)
			(layer "B.Fab")
		)
		(fp_line
			(start 0.67945 -0.305054)
			(end 0.12065 -0.305054)
			(stroke
				(width 0.1)
				(type default)
			)
			(layer "B.Fab")
		)
		(fp_line
			(start 0.12065 0.3048)
			(end 0.67945 0.3048)
			(stroke
				(width 0.1)
				(type default)
			)
			(layer "B.Fab")
		)
		(fp_line
			(start 0.12065 0.2794)
			(end 0.12065 0.3048)
			(stroke
				(width 0.1)
				(type default)
			)
			(layer "B.Fab")
		)
		(fp_line
			(start 0.12065 -0.2794)
			(end -0.12065 -0.2794)
			(stroke
				(width 0.1)
				(type default)
			)
			(layer "B.Fab")
		)
		(fp_line
			(start 0.12065 -0.305054)
			(end 0.12065 -0.2794)
			(stroke
				(width 0.1)
				(type default)
			)
			(layer "B.Fab")
		)
		(fp_line
			(start -0.120396 0.3048)
			(end -0.120396 0.2794)
			(stroke
				(width 0.1)
				(type default)
			)
			(layer "B.Fab")
		)
		(fp_line
			(start -0.120396 0.2794)
			(end 0.12065 0.2794)
			(stroke
				(width 0.1)
				(type default)
			)
			(layer "B.Fab")
		)
		(fp_line
			(start -0.12065 -0.2794)
			(end -0.12065 -0.3048)
			(stroke
				(width 0.1)
				(type default)
			)
			(layer "B.Fab")
		)
		(fp_line
			(start -0.12065 -0.3048)
			(end -0.67945 -0.3048)
			(stroke
				(width 0.1)
				(type default)
			)
			(layer "B.Fab")
		)
		(fp_line
			(start -0.67945 0.3048)
			(end -0.120396 0.3048)
			(stroke
				(width 0.1)
				(type default)
			)
			(layer "B.Fab")
		)
		(fp_line
			(start -0.67945 -0.3048)
			(end -0.67945 0.3048)
			(stroke
				(width 0.1)
				(type default)
			)
			(layer "B.Fab")
		)
		(pad "1" smd circle
			(at 0.40005 0)
			(size 0 0)
			(layers "B.Cu" "B.Mask" "B.Paste")
			(net "PVDDCR_SOC_P0")
		)
		(pad "2" smd circle
			(at -0.40005 0)
			(size 0 0)
			(layers "B.Cu" "B.Mask" "B.Paste")
			(net "GND")
		)
	)
)
